(kicad_pcb
	(version 20260206)
	(generator "pcbnew")
	(generator_version "10.0")
	(general
		(thickness 1.6)
		(legacy_teardrops no)
	)
	(paper "A4")
	(title_block
		(title "04192023_DAF0TMB3IC0_F0TG_MB_C_brd_V02_OCP.brd")
		(comment 1 "Grand Teton / footprints 5758-5763 of 8354")
	)
	(layers
		(0 "F.Cu" signal "TOP")
		(4 "In1.Cu" signal "GND")
		(6 "In2.Cu" signal "IN1")
		(8 "In3.Cu" signal "GND1")
		(10 "In4.Cu" signal "IN2")
		(12 "In5.Cu" signal "GND2")
		(14 "In6.Cu" signal "IN3")
		(16 "In7.Cu" signal "GND3")
		(18 "In8.Cu" signal "VCC")
		(20 "In9.Cu" signal "VCC1")
		(22 "In10.Cu" signal "GND4")
		(24 "In11.Cu" signal "IN4")
		(26 "In12.Cu" signal "GND5")
		(28 "In13.Cu" signal "IN5")
		(30 "In14.Cu" signal "GND6")
		(32 "In15.Cu" signal "IN6")
		(34 "In16.Cu" signal "GND7")
		(2 "B.Cu" signal "BOTTOM")
		(9 "F.Adhes" user "F.Adhesive")
		(11 "B.Adhes" user "B.Adhesive")
		(13 "F.Paste" user "Package Geometry/Pastemask Top")
		(15 "B.Paste" user "Package Geometry/Pastemask Bottom")
		(5 "F.SilkS" user "Ref Des/Silkscreen Top")
		(7 "B.SilkS" user "Ref Des/Silkscreen Bottom")
		(1 "F.Mask" user "Board Geometry/Soldermask Top")
		(3 "B.Mask" user "Board Geometry/Soldermask Bottom")
		(17 "Dwgs.User" user "User.Drawings")
		(19 "Cmts.User" user "User.Comments")
		(21 "Eco1.User" user "User.Eco1")
		(23 "Eco2.User" user "User.Eco2")
		(25 "Edge.Cuts" user "Board Geometry/Outline")
		(27 "Margin" user)
		(31 "F.CrtYd" user "Package Geometry/Place Bound Top")
		(29 "B.CrtYd" user "Package Geometry/Place Bound Bottom")
		(35 "F.Fab" user "Ref Des/Assembly Top")
		(33 "B.Fab" user "Ref Des/Assembly Bottom")
	)
	(footprint ""
		(layer "B.Cu")
		(at 48.555148 -194.885564 180)
		(property "Reference" "R770"
			(at 0 0 0)
			(layer "B.SilkS")
			(hide yes)
			(effects
				(font
					(size 1.27 1.27)
				)
				(justify mirror)
			)
		)
		(property "Value" ""
			(at 0 0 0)
			(layer "B.Fab")
			(effects
				(font
					(size 1.27 1.27)
				)
				(justify mirror)
			)
		)
		(duplicate_pad_numbers_are_jumpers no)
		(fp_line
			(start 0.7874 0.4064)
			(end 0.7874 -0.4064)
			(stroke
				(width 0.1524)
				(type default)
			)
			(layer "B.SilkS")
		)
		(fp_line
			(start 0.7874 -0.4064)
			(end -0.7874 -0.4064)
			(stroke
				(width 0.1524)
				(type default)
			)
			(layer "B.SilkS")
		)
		(fp_line
			(start -0.7874 0.4064)
			(end 0.7874 0.4064)
			(stroke
				(width 0.1524)
				(type default)
			)
			(layer "B.SilkS")
		)
		(fp_line
			(start -0.7874 -0.4064)
			(end -0.7874 0.4064)
			(stroke
				(width 0.1524)
				(type default)
			)
			(layer "B.SilkS")
		)
		(fp_line
			(start 0.67945 0.3048)
			(end 0.67945 -0.305054)
			(stroke
				(width 0.1)
				(type default)
			)
			(layer "B.Fab")
		)
		(fp_line
			(start 0.67945 -0.305054)
			(end 0.12065 -0.305054)
			(stroke
				(width 0.1)
				(type default)
			)
			(layer "B.Fab")
		)
		(fp_line
			(start 0.12065 0.3048)
			(end 0.67945 0.3048)
			(stroke
				(width 0.1)
				(type default)
			)
			(layer "B.Fab")
		)
		(fp_line
			(start 0.12065 0.2794)
			(end 0.12065 0.3048)
			(stroke
				(width 0.1)
				(type default)
			)
			(layer "B.Fab")
		)
		(fp_line
			(start 0.12065 -0.2794)
			(end -0.12065 -0.2794)
			(stroke
				(width 0.1)
				(type default)
			)
			(layer "B.Fab")
		)
		(fp_line
			(start 0.12065 -0.305054)
			(end 0.12065 -0.2794)
			(stroke
				(width 0.1)
				(type default)
			)
			(layer "B.Fab")
		)
		(fp_line
			(start -0.120396 0.3048)
			(end -0.120396 0.2794)
			(stroke
				(width 0.1)
				(type default)
			)
			(layer "B.Fab")
		)
		(fp_line
			(start -0.120396 0.2794)
			(end 0.12065 0.2794)
			(stroke
				(width 0.1)
				(type default)
			)
			(layer "B.Fab")
		)
		(fp_line
			(start -0.12065 -0.2794)
			(end -0.12065 -0.3048)
			(stroke
				(width 0.1)
				(type default)
			)
			(layer "B.Fab")
		)
		(fp_line
			(start -0.12065 -0.3048)
			(end -0.67945 -0.3048)
			(stroke
				(width 0.1)
				(type default)
			)
			(layer "B.Fab")
		)
		(fp_line
			(start -0.67945 0.3048)
			(end -0.120396 0.3048)
			(stroke
				(width 0.1)
				(type default)
			)
			(layer "B.Fab")
		)
		(fp_line
			(start -0.67945 -0.3048)
			(end -0.67945 0.3048)
			(stroke
				(width 0.1)
				(type default)
			)
			(layer "B.Fab")
		)
		(pad "1" smd circle
			(at 0.40005 0)
			(size 0 0)
			(layers "B.Cu" "B.Mask" "B.Paste")
			(net "PD_CHB_CPU1_DIMM_SAA")
		)
		(pad "2" smd circle
			(at -0.40005 0)
			(size 0 0)
			(layers "B.Cu" "B.Mask" "B.Paste")
			(net "GND")
		)
	)
	(footprint ""
		(layer "B.Cu")
		(at 384.89128 -398.942052 90)
		(property "Reference" "C1023"
			(at 0 0 90)
			(layer "B.SilkS")
			(hide yes)
			(effects
				(font
					(size 1.27 1.27)
				)
				(justify mirror)
			)
		)
		(property "Value" ""
			(at 0 0 90)
			(layer "B.Fab")
			(effects
				(font
					(size 1.27 1.27)
				)
				(justify mirror)
			)
		)
		(duplicate_pad_numbers_are_jumpers no)
		(fp_line
			(start 0.7874 -0.4064)
			(end -0.7874 -0.4064)
			(stroke
				(width 0.1524)
				(type default)
			)
			(layer "B.SilkS")
		)
		(fp_line
			(start -0.7874 -0.4064)
			(end -0.7874 0.4064)
			(stroke
				(width 0.1524)
				(type default)
			)
			(layer "B.SilkS")
		)
		(fp_line
			(start 0.7874 0.4064)
			(end 0.7874 -0.4064)
			(stroke
				(width 0.1524)
				(type default)
			)
			(layer "B.SilkS")
		)
		(fp_line
			(start -0.7874 0.4064)
			(end 0.7874 0.4064)
			(stroke
				(width 0.1524)
				(type default)
			)
			(layer "B.SilkS")
		)
		(fp_line
			(start 0.67945 -0.305054)
			(end 0.12065 -0.305054)
			(stroke
				(width 0.1)
				(type default)
			)
			(layer "B.Fab")
		)
		(fp_line
			(start 0.12065 -0.305054)
			(end 0.12065 -0.2794)
			(stroke
				(width 0.1)
				(type default)
			)
			(layer "B.Fab")
		)
		(fp_line
			(start -0.12065 -0.3048)
			(end -0.67945 -0.3048)
			(stroke
				(width 0.1)
				(type default)
			)
			(layer "B.Fab")
		)
		(fp_line
			(start -0.67945 -0.3048)
			(end -0.67945 0.3048)
			(stroke
				(width 0.1)
				(type default)
			)
			(layer "B.Fab")
		)
		(fp_line
			(start 0.12065 -0.2794)
			(end -0.12065 -0.2794)
			(stroke
				(width 0.1)
				(type default)
			)
			(layer "B.Fab")
		)
		(fp_line
			(start -0.12065 -0.2794)
			(end -0.12065 -0.3048)
			(stroke
				(width 0.1)
				(type default)
			)
			(layer "B.Fab")
		)
		(fp_line
			(start 0.12065 0.2794)
			(end 0.12065 0.3048)
			(stroke
				(width 0.1)
				(type default)
			)
			(layer "B.Fab")
		)
		(fp_line
			(start -0.120396 0.2794)
			(end 0.12065 0.2794)
			(stroke
				(width 0.1)
				(type default)
			)
			(layer "B.Fab")
		)
		(fp_line
			(start 0.67945 0.3048)
			(end 0.67945 -0.305054)
			(stroke
				(width 0.1)
				(type default)
			)
			(layer "B.Fab")
		)
		(fp_line
			(start 0.12065 0.3048)
			(end 0.67945 0.3048)
			(stroke
				(width 0.1)
				(type default)
			)
			(layer "B.Fab")
		)
		(fp_line
			(start -0.120396 0.3048)
			(end -0.120396 0.2794)
			(stroke
				(width 0.1)
				(type default)
			)
			(layer "B.Fab")
		)
		(fp_line
			(start -0.67945 0.3048)
			(end -0.120396 0.3048)
			(stroke
				(width 0.1)
				(type default)
			)
			(layer "B.Fab")
		)
		(pad "1" smd circle
			(at 0.40005 0 270)
			(size 0 0)
			(layers "B.Cu" "B.Mask" "B.Paste")
			(net "P0V9_CPU0_RT3_2A")
		)
		(pad "2" smd circle
			(at -0.40005 0 270)
			(size 0 0)
			(layers "B.Cu" "B.Mask" "B.Paste")
			(net "GND")
		)
	)
	(footprint ""
		(layer "B.Cu")
		(at 113.705386 -251.781564)
		(property "Reference" "C2281"
			(at 0 0 0)
			(layer "B.SilkS")
			(hide yes)
			(effects
				(font
					(size 1.27 1.27)
				)
				(justify mirror)
			)
		)
		(property "Value" ""
			(at 0 0 0)
			(layer "B.Fab")
			(effects
				(font
					(size 1.27 1.27)
				)
				(justify mirror)
			)
		)
		(duplicate_pad_numbers_are_jumpers no)
		(fp_line
			(start -0.7874 -0.4064)
			(end -0.7874 0.4064)
			(stroke
				(width 0.1524)
				(type default)
			)
			(layer "B.SilkS")
		)
		(fp_line
			(start -0.7874 0.4064)
			(end 0.7874 0.4064)
			(stroke
				(width 0.1524)
				(type default)
			)
			(layer "B.SilkS")
		)
		(fp_line
			(start 0.7874 -0.4064)
			(end -0.7874 -0.4064)
			(stroke
				(width 0.1524)
				(type default)
			)
			(layer "B.SilkS")
		)
		(fp_line
			(start 0.7874 0.4064)
			(end 0.7874 -0.4064)
			(stroke
				(width 0.1524)
				(type default)
			)
			(layer "B.SilkS")
		)
		(fp_line
			(start -0.67945 -0.3048)
			(end -0.67945 0.3048)
			(stroke
				(width 0.1)
				(type default)
			)
			(layer "B.Fab")
		)
		(fp_line
			(start -0.67945 0.3048)
			(end -0.120396 0.3048)
			(stroke
				(width 0.1)
				(type default)
			)
			(layer "B.Fab")
		)
		(fp_line
			(start -0.12065 -0.3048)
			(end -0.67945 -0.3048)
			(stroke
				(width 0.1)
				(type default)
			)
			(layer "B.Fab")
		)
		(fp_line
			(start -0.12065 -0.2794)
			(end -0.12065 -0.3048)
			(stroke
				(width 0.1)
				(type default)
			)
			(layer "B.Fab")
		)
		(fp_line
			(start -0.120396 0.2794)
			(end 0.12065 0.2794)
			(stroke
				(width 0.1)
				(type default)
			)
			(layer "B.Fab")
		)
		(fp_line
			(start -0.120396 0.3048)
			(end -0.120396 0.2794)
			(stroke
				(width 0.1)
				(type default)
			)
			(layer "B.Fab")
		)
		(fp_line
			(start 0.12065 -0.305054)
			(end 0.12065 -0.2794)
			(stroke
				(width 0.1)
				(type default)
			)
			(layer "B.Fab")
		)
		(fp_line
			(start 0.12065 -0.2794)
			(end -0.12065 -0.2794)
			(stroke
				(width 0.1)
				(type default)
			)
			(layer "B.Fab")
		)
		(fp_line
			(start 0.12065 0.2794)
			(end 0.12065 0.3048)
			(stroke
				(width 0.1)
				(type default)
			)
			(layer "B.Fab")
		)
		(fp_line
			(start 0.12065 0.3048)
			(end 0.67945 0.3048)
			(stroke
				(width 0.1)
				(type default)
			)
			(layer "B.Fab")
		)
		(fp_line
			(start 0.67945 -0.305054)
			(end 0.12065 -0.305054)
			(stroke
				(width 0.1)
				(type default)
			)
			(layer "B.Fab")
		)
		(fp_line
			(start 0.67945 0.3048)
			(end 0.67945 -0.305054)
			(stroke
				(width 0.1)
				(type default)
			)
			(layer "B.Fab")
		)
		(pad "1" smd circle
			(at 0.40005 0 180)
			(size 0 0)
			(layers "B.Cu" "B.Mask" "B.Paste")
			(net "PVDDCR_SOC_P1")
		)
		(pad "2" smd circle
			(at -0.40005 0 180)
			(size 0 0)
			(layers "B.Cu" "B.Mask" "B.Paste")
			(net "GND")
		)
	)
	(footprint ""
		(layer "B.Cu")
		(at 332.316836 -76.35875 180)
		(property "Reference" "Q83"
			(at -2.243328 2.223008 0)
			(unlocked yes)
			(layer "B.SilkS")
			(effects
				(font
					(size 0.7874 0.5842)
					(thickness 0.1524)
				)
				(justify left mirror)
			)
		)
		(property "Value" ""
			(at 0 0 0)
			(layer "B.Fab")
			(effects
				(font
					(size 1.27 1.27)
				)
				(justify mirror)
			)
		)
		(duplicate_pad_numbers_are_jumpers no)
		(fp_line
			(start 1.332738 1.100074)
			(end 1.332738 -1.100074)
			(stroke
				(width 0.1524)
				(type default)
			)
			(layer "B.SilkS")
		)
		(fp_line
			(start 1.332738 -1.100074)
			(end 0.4826 -1.100074)
			(stroke
				(width 0.1524)
				(type default)
			)
			(layer "B.SilkS")
		)
		(fp_line
			(start 0.4826 -1.100074)
			(end 0 -0.541274)
			(stroke
				(width 0.1524)
				(type default)
			)
			(layer "B.SilkS")
		)
		(fp_line
			(start 0 -0.541274)
			(end -0.4826 -1.100074)
			(stroke
				(width 0.1524)
				(type default)
			)
			(layer "B.SilkS")
		)
		(fp_line
			(start -0.4826 -1.100074)
			(end -1.332738 -1.100074)
			(stroke
				(width 0.1524)
				(type default)
			)
			(layer "B.SilkS")
		)
		(fp_line
			(start -1.332738 1.100074)
			(end 1.332738 1.100074)
			(stroke
				(width 0.1524)
				(type default)
			)
			(layer "B.SilkS")
		)
		(fp_line
			(start -1.332738 -1.100074)
			(end -1.332738 1.100074)
			(stroke
				(width 0.1524)
				(type default)
			)
			(layer "B.SilkS")
		)
		(fp_poly
			(pts
				(xy 1.864106 -0.627888) (xy 2.566162 -0.978916) (xy 2.566162 -0.27686)
			)
			(stroke
				(width 0)
				(type default)
			)
			(fill yes)
			(layer "B.SilkS")
		)
		(fp_line
			(start 0.674878 1.100074)
			(end 0.674878 -1.100074)
			(stroke
				(width 0.1)
				(type default)
			)
			(layer "B.Fab")
		)
		(fp_line
			(start 0.674878 -1.100074)
			(end -0.674878 -1.100074)
			(stroke
				(width 0.1)
				(type default)
			)
			(layer "B.Fab")
		)
		(fp_line
			(start -0.674878 1.100074)
			(end 0.674878 1.100074)
			(stroke
				(width 0.1)
				(type default)
			)
			(layer "B.Fab")
		)
		(fp_line
			(start -0.674878 -1.100074)
			(end -0.674878 1.100074)
			(stroke
				(width 0.1)
				(type default)
			)
			(layer "B.Fab")
		)
		(fp_poly
			(pts
				(xy 2.2352 -0.298958) (xy 2.2352 -1.001014) (xy 1.533144 -0.649986)
			)
			(stroke
				(width 0)
				(type default)
			)
			(fill yes)
			(layer "B.Fab")
		)
		(pad "1" smd rect
			(at 0.94996 -0.649986 270)
			(size 0.4318 0.508)
			(layers "B.Cu" "B.Mask" "B.Paste")
			(net "GND")
		)
		(pad "2" smd rect
			(at 0.94996 0 270)
			(size 0.4318 0.508)
			(layers "B.Cu" "B.Mask" "B.Paste")
			(net "FM_LED_PWRGD_PVDD18_S5_P0")
		)
		(pad "3" smd rect
			(at 0.94996 0.649986 270)
			(size 0.4318 0.508)
			(layers "B.Cu" "B.Mask" "B.Paste")
			(net "NC_Q83_D2")
		)
		(pad "4" smd rect
			(at -0.94996 0.649986 270)
			(size 0.4318 0.508)
			(layers "B.Cu" "B.Mask" "B.Paste")
			(net "NC_Q83_S2")
		)
		(pad "5" smd rect
			(at -0.94996 0 270)
			(size 0.4318 0.508)
			(layers "B.Cu" "B.Mask" "B.Paste")
			(net "NC_Q83_G2")
		)
		(pad "6" smd rect
			(at -0.94996 -0.649986 270)
			(size 0.4318 0.508)
			(layers "B.Cu" "B.Mask" "B.Paste")
			(net "LED_PWRGD_PVDD18_S5_P0_D")
		)
	)
	(footprint ""
		(layer "B.Cu")
		(at 24.404574 -373.339614 90)
		(property "Reference" "PC6814"
			(at -3.896614 2.873756 270)
			(unlocked yes)
			(layer "B.SilkS")
			(effects
				(font
					(size 0.7874 0.5842)
					(thickness 0.1524)
				)
				(justify left mirror)
			)
		)
		(property "Value" ""
			(at 0 0 90)
			(layer "B.Fab")
			(effects
				(font
					(size 1.27 1.27)
				)
				(justify mirror)
			)
		)
		(duplicate_pad_numbers_are_jumpers no)
		(fp_line
			(start 4.84378 -2.150618)
			(end 4.53898 -2.150618)
			(stroke
				(width 0.1524)
				(type default)
			)
			(layer "B.SilkS")
		)
		(fp_line
			(start 4.84378 -2.150618)
			(end 4.842256 2.163064)
			(stroke
				(width 0.1524)
				(type default)
			)
			(layer "B.SilkS")
		)
		(fp_line
			(start 4.69138 -2.150618)
			(end 4.692396 2.161032)
			(stroke
				(width 0.1524)
				(type default)
			)
			(layer "B.SilkS")
		)
		(fp_line
			(start 4.53898 -2.150618)
			(end 4.539742 2.152142)
			(stroke
				(width 0.1524)
				(type default)
			)
			(layer "B.SilkS")
		)
		(fp_line
			(start 4.53898 -2.15011)
			(end -3.871214 -2.15011)
			(stroke
				(width 0.1524)
				(type default)
			)
			(layer "B.SilkS")
		)
		(fp_line
			(start -4.53898 -1.849374)
			(end -4.53898 2.15011)
			(stroke
				(width 0.1524)
				(type default)
			)
			(layer "B.SilkS")
		)
		(fp_line
			(start 4.53898 2.15011)
			(end 4.53898 -2.15011)
			(stroke
				(width 0.1524)
				(type default)
			)
			(layer "B.SilkS")
		)
		(fp_line
			(start -4.53898 2.15011)
			(end 4.53898 2.15011)
			(stroke
				(width 0.1524)
				(type default)
			)
			(layer "B.SilkS")
		)
		(fp_line
			(start 4.83108 2.150364)
			(end 4.447794 2.149348)
			(stroke
				(width 0.1524)
				(type default)
			)
			(layer "B.SilkS")
		)
		(fp_line
			(start 3.64998 -2.15011)
			(end -3.64998 -2.15011)
			(stroke
				(width 0.1)
				(type default)
			)
			(layer "B.Fab")
		)
		(fp_line
			(start -3.64998 -2.15011)
			(end -3.64998 2.15011)
			(stroke
				(width 0.1)
				(type default)
			)
			(layer "B.Fab")
		)
		(fp_line
			(start 3.64998 2.15011)
			(end 3.64998 -2.15011)
			(stroke
				(width 0.1)
				(type default)
			)
			(layer "B.Fab")
		)
		(fp_line
			(start -3.64998 2.15011)
			(end 3.64998 2.15011)
			(stroke
				(width 0.1)
				(type default)
			)
			(layer "B.Fab")
		)
		(fp_text user "-"
			(at -4.313174 -0.094488 90)
			(unlocked yes)
			(layer "B.SilkS")
			(effects
				(font
					(size 1.905 1.4224)
					(thickness 0.1524)
				)
				(justify left mirror)
			)
		)
		(fp_text user "+"
			(at 6.839712 1.525778 90)
			(unlocked yes)
			(layer "B.SilkS")
			(effects
				(font
					(size 1.905 1.4224)
					(thickness 0.1524)
				)
				(justify left mirror)
			)
		)
		(fp_text user "+"
			(at 6.214872 -0.337058 90)
			(unlocked yes)
			(layer "B.Fab")
			(effects
				(font
					(size 1.905 1.4224)
					(thickness 0.1524)
				)
				(justify left mirror)
			)
		)
		(fp_text user "-"
			(at -4.313174 -0.094488 90)
			(unlocked yes)
			(layer "B.Fab")
			(effects
				(font
					(size 1.905 1.4224)
					(thickness 0.1524)
				)
				(justify left mirror)
			)
		)
		(pad "1" smd rect
			(at 3.199892 0 270)
			(size 2.413 2.8194)
			(layers "B.Cu" "B.Mask" "B.Paste")
			(net "P0V9_CPU1_RT_2D")
		)
		(pad "2" smd rect
			(at -3.199892 0 270)
			(size 2.413 2.8194)
			(layers "B.Cu" "B.Mask" "B.Paste")
			(net "GND")
		)
	)
	(footprint ""
		(layer "B.Cu")
		(at 145.197068 -381.50419)
		(property "Reference" "C7028"
			(at 0 0 0)
			(layer "B.SilkS")
			(hide yes)
			(effects
				(font
					(size 1.27 1.27)
				)
				(justify mirror)
			)
		)
		(property "Value" ""
			(at 0 0 0)
			(layer "B.Fab")
			(effects
				(font
					(size 1.27 1.27)
				)
				(justify mirror)
			)
		)
		(duplicate_pad_numbers_are_jumpers no)
		(fp_line
			(start -1.524 -0.762)
			(end -1.524 0.762)
			(stroke
				(width 0.1524)
				(type default)
			)
			(layer "B.SilkS")
		)
		(fp_line
			(start -1.524 0.762)
			(end 1.524 0.762)
			(stroke
				(width 0.1524)
				(type default)
			)
			(layer "B.SilkS")
		)
		(fp_line
			(start 1.524 -0.762)
			(end -1.524 -0.762)
			(stroke
				(width 0.1524)
				(type default)
			)
			(layer "B.SilkS")
		)
		(fp_line
			(start 1.524 0.762)
			(end 1.524 -0.762)
			(stroke
				(width 0.1524)
				(type default)
			)
			(layer "B.SilkS")
		)
		(fp_line
			(start -1.1049 -0.724916)
			(end 1.1049 -0.724916)
			(stroke
				(width 0.1)
				(type default)
			)
			(layer "B.Fab")
		)
		(fp_line
			(start -1.1049 0.724916)
			(end -1.1049 -0.724916)
			(stroke
				(width 0.1)
				(type default)
			)
			(layer "B.Fab")
		)
		(fp_line
			(start 1.1049 -0.724916)
			(end 1.1049 0.724916)
			(stroke
				(width 0.1)
				(type default)
			)
			(layer "B.Fab")
		)
		(fp_line
			(start 1.1049 0.724916)
			(end -1.1049 0.724916)
			(stroke
				(width 0.1)
				(type default)
			)
			(layer "B.Fab")
		)
		(pad "1" smd rect
			(at 0.889 0)
			(size 1.016 1.27)
			(layers "B.Cu" "B.Mask" "B.Paste")
			(net "P0V9_CPU1_RT2_2A")
		)
		(pad "2" smd rect
			(at -0.889 0)
			(size 1.016 1.27)
			(layers "B.Cu" "B.Mask" "B.Paste")
			(net "GND")
		)
	)
)
